# T6G (Grand Teton) — schematic netlist excerpt (pin names and nets, part order shuffled) for the footprints in the layout excerpt that follows; sources: Cadence DE-HDL packaged netlist, KiCad conversion of 04192023_DAF0TMB3IC0_F0TG_MB_C_brd_V02_OCP.brd

C5006  Q_CAP  1000PF 50V 5% X7R  pkg 0402  page 217 : A = GND ; B = PWRGD_PVDDIO_P1
R771  Q_RES  23.2K 1% CHIP  pkg 0402LF  page 100 : A = PD_CHC_CPU1_DIMM_SAA ; B = GND
C165  Q_CAP  10UF 25V 10% X6S  pkg C0805  page 95 : A = P12V_MEM_CPU0 ; B = GND

(kicad_pcb
	(version 20260206)
	(generator "pcbnew")
	(generator_version "10.0")
	(general
		(thickness 1.6)
		(legacy_teardrops no)
	)
	(paper "A4")
	(title_block
		(title "04192023_DAF0TMB3IC0_F0TG_MB_C_brd_V02_OCP.brd")
		(comment 1 "Grand Teton / footprints 8244-8246 of 8354")
	)
	(layers
		(0 "F.Cu" signal "TOP")
		(4 "In1.Cu" signal "GND")
		(6 "In2.Cu" signal "IN1")
		(8 "In3.Cu" signal "GND1")
		(10 "In4.Cu" signal "IN2")
		(12 "In5.Cu" signal "GND2")
		(14 "In6.Cu" signal "IN3")
		(16 "In7.Cu" signal "GND3")
		(18 "In8.Cu" signal "VCC")
		(20 "In9.Cu" signal "VCC1")
		(22 "In10.Cu" signal "GND4")
		(24 "In11.Cu" signal "IN4")
		(26 "In12.Cu" signal "GND5")
		(28 "In13.Cu" signal "IN5")
		(30 "In14.Cu" signal "GND6")
		(32 "In15.Cu" signal "IN6")
		(34 "In16.Cu" signal "GND7")
		(2 "B.Cu" signal "BOTTOM")
		(9 "F.Adhes" user "F.Adhesive")
		(11 "B.Adhes" user "B.Adhesive")
		(13 "F.Paste" user "Package Geometry/Pastemask Top")
		(15 "B.Paste" user "Package Geometry/Pastemask Bottom")
		(5 "F.SilkS" user "Ref Des/Silkscreen Top")
		(7 "B.SilkS" user "Ref Des/Silkscreen Bottom")
		(1 "F.Mask" user "Board Geometry/Soldermask Top")
		(3 "B.Mask" user "Board Geometry/Soldermask Bottom")
		(17 "Dwgs.User" user "User.Drawings")
		(19 "Cmts.User" user "User.Comments")
		(21 "Eco1.User" user "User.Eco1")
		(23 "Eco2.User" user "User.Eco2")
		(25 "Edge.Cuts" user "Board Geometry/Outline")
		(27 "Margin" user)
		(31 "F.CrtYd" user "Package Geometry/Place Bound Top")
		(29 "B.CrtYd" user "Package Geometry/Place Bound Bottom")
		(35 "F.Fab" user "Ref Des/Assembly Top")
		(33 "B.Fab" user "Ref Des/Assembly Bottom")
	)
	(footprint ""
		(layer "B.Cu")
		(at 435.000146 -192.660016 180)
		(property "Reference" "C165"
			(at 0 0 0)
			(layer "B.SilkS")
			(hide yes)
			(effects
				(font
					(size 1.27 1.27)
				)
				(justify mirror)
			)
		)
		(property "Value" ""
			(at 0 0 0)
			(layer "B.Fab")
			(effects
				(font
					(size 1.27 1.27)
				)
				(justify mirror)
			)
		)
		(duplicate_pad_numbers_are_jumpers no)
		(fp_line
			(start 1.524 0.762)
			(end 1.524 -0.762)
			(stroke
				(width 0.1524)
				(type default)
			)
			(layer "B.SilkS")
		)
		(fp_line
			(start 1.524 -0.762)
			(end -1.524 -0.762)
			(stroke
				(width 0.1524)
				(type default)
			)
			(layer "B.SilkS")
		)
		(fp_line
			(start -1.524 0.762)
			(end 1.524 0.762)
			(stroke
				(width 0.1524)
				(type default)
			)
			(layer "B.SilkS")
		)
		(fp_line
			(start -1.524 -0.762)
			(end -1.524 0.762)
			(stroke
				(width 0.1524)
				(type default)
			)
			(layer "B.SilkS")
		)
		(fp_line
			(start 1.1049 0.724916)
			(end -1.1049 0.724916)
			(stroke
				(width 0.1)
				(type default)
			)
			(layer "B.Fab")
		)
		(fp_line
			(start 1.1049 -0.724916)
			(end 1.1049 0.724916)
			(stroke
				(width 0.1)
				(type default)
			)
			(layer "B.Fab")
		)
		(fp_line
			(start -1.1049 0.724916)
			(end -1.1049 -0.724916)
			(stroke
				(width 0.1)
				(type default)
			)
			(layer "B.Fab")
		)
		(fp_line
			(start -1.1049 -0.724916)
			(end 1.1049 -0.724916)
			(stroke
				(width 0.1)
				(type default)
			)
			(layer "B.Fab")
		)
		(pad "1" smd rect
			(at 0.889 0 180)
			(size 1.016 1.27)
			(layers "B.Cu" "B.Mask" "B.Paste")
			(net "P12V_MEM_CPU0")
		)
		(pad "2" smd rect
			(at -0.889 0 180)
			(size 1.016 1.27)
			(layers "B.Cu" "B.Mask" "B.Paste")
			(net "GND")
		)
	)
	(footprint ""
		(layer "B.Cu")
		(at 22.479 -362.204 180)
		(property "Reference" "C5006"
			(at 0 0 0)
			(layer "B.SilkS")
			(hide yes)
			(effects
				(font
					(size 1.27 1.27)
				)
				(justify mirror)
			)
		)
		(property "Value" ""
			(at 0 0 0)
			(layer "B.Fab")
			(effects
				(font
					(size 1.27 1.27)
				)
				(justify mirror)
			)
		)
		(duplicate_pad_numbers_are_jumpers no)
		(fp_line
			(start 0.7874 0.4064)
			(end 0.7874 -0.4064)
			(stroke
				(width 0.1524)
				(type default)
			)
			(layer "B.SilkS")
		)
		(fp_line
			(start 0.7874 -0.4064)
			(end -0.7874 -0.4064)
			(stroke
				(width 0.1524)
				(type default)
			)
			(layer "B.SilkS")
		)
		(fp_line
			(start -0.7874 0.4064)
			(end 0.7874 0.4064)
			(stroke
				(width 0.1524)
				(type default)
			)
			(layer "B.SilkS")
		)
		(fp_line
			(start -0.7874 -0.4064)
			(end -0.7874 0.4064)
			(stroke
				(width 0.1524)
				(type default)
			)
			(layer "B.SilkS")
		)
		(fp_line
			(start 0.67945 0.3048)
			(end 0.67945 -0.305054)
			(stroke
				(width 0.1)
				(type default)
			)
			(layer "B.Fab")
		)
		(fp_line
			(start 0.67945 -0.305054)
			(end 0.12065 -0.305054)
			(stroke
				(width 0.1)
				(type default)
			)
			(layer "B.Fab")
		)
		(fp_line
			(start 0.12065 0.3048)
			(end 0.67945 0.3048)
			(stroke
				(width 0.1)
				(type default)
			)
			(layer "B.Fab")
		)
		(fp_line
			(start 0.12065 0.2794)
			(end 0.12065 0.3048)
			(stroke
				(width 0.1)
				(type default)
			)
			(layer "B.Fab")
		)
		(fp_line
			(start 0.12065 -0.2794)
			(end -0.12065 -0.2794)
			(stroke
				(width 0.1)
				(type default)
			)
			(layer "B.Fab")
		)
		(fp_line
			(start 0.12065 -0.305054)
			(end 0.12065 -0.2794)
			(stroke
				(width 0.1)
				(type default)
			)
			(layer "B.Fab")
		)
		(fp_line
			(start -0.120396 0.3048)
			(end -0.120396 0.2794)
			(stroke
				(width 0.1)
				(type default)
			)
			(layer "B.Fab")
		)
		(fp_line
			(start -0.120396 0.2794)
			(end 0.12065 0.2794)
			(stroke
				(width 0.1)
				(type default)
			)
			(layer "B.Fab")
		)
		(fp_line
			(start -0.12065 -0.2794)
			(end -0.12065 -0.3048)
			(stroke
				(width 0.1)
				(type default)
			)
			(layer "B.Fab")
		)
		(fp_line
			(start -0.12065 -0.3048)
			(end -0.67945 -0.3048)
			(stroke
				(width 0.1)
				(type default)
			)
			(layer "B.Fab")
		)
		(fp_line
			(start -0.67945 0.3048)
			(end -0.120396 0.3048)
			(stroke
				(width 0.1)
				(type default)
			)
			(layer "B.Fab")
		)
		(fp_line
			(start -0.67945 -0.3048)
			(end -0.67945 0.3048)
			(stroke
				(width 0.1)
				(type default)
			)
			(layer "B.Fab")
		)
		(pad "1" smd circle
			(at 0.40005 0)
			(size 0 0)
			(layers "B.Cu" "B.Mask" "B.Paste")
			(net "GND")
		)
		(pad "2" smd circle
			(at -0.40005 0)
			(size 0 0)
			(layers "B.Cu" "B.Mask" "B.Paste")
			(net "PWRGD_PVDDIO_P1")
		)
	)
	(footprint ""
		(layer "B.Cu")
		(at 40.9956 -194.885564 180)
		(property "Reference" "R771"
			(at 0 0 0)
			(layer "B.SilkS")
			(hide yes)
			(effects
				(font
					(size 1.27 1.27)
				)
				(justify mirror)
			)
		)
		(property "Value" ""
			(at 0 0 0)
			(layer "B.Fab")
			(effects
				(font
					(size 1.27 1.27)
				)
				(justify mirror)
			)
		)
		(duplicate_pad_numbers_are_jumpers no)
		(fp_line
			(start 0.7874 0.4064)
			(end 0.7874 -0.4064)
			(stroke
				(width 0.1524)
				(type default)
			)
			(layer "B.SilkS")
		)
		(fp_line
			(start 0.7874 -0.4064)
			(end -0.7874 -0.4064)
			(stroke
				(width 0.1524)
				(type default)
			)
			(layer "B.SilkS")
		)
		(fp_line
			(start -0.7874 0.4064)
			(end 0.7874 0.4064)
			(stroke
				(width 0.1524)
				(type default)
			)
			(layer "B.SilkS")
		)
		(fp_line
			(start -0.7874 -0.4064)
			(end -0.7874 0.4064)
			(stroke
				(width 0.1524)
				(type default)
			)
			(layer "B.SilkS")
		)
		(fp_line
			(start 0.67945 0.3048)
			(end 0.67945 -0.305054)
			(stroke
				(width 0.1)
				(type default)
			)
			(layer "B.Fab")
		)
		(fp_line
			(start 0.67945 -0.305054)
			(end 0.12065 -0.305054)
			(stroke
				(width 0.1)
				(type default)
			)
			(layer "B.Fab")
		)
		(fp_line
			(start 0.12065 0.3048)
			(end 0.67945 0.3048)
			(stroke
				(width 0.1)
				(type default)
			)
			(layer "B.Fab")
		)
		(fp_line
			(start 0.12065 0.2794)
			(end 0.12065 0.3048)
			(stroke
				(width 0.1)
				(type default)
			)
			(layer "B.Fab")
		)
		(fp_line
			(start 0.12065 -0.2794)
			(end -0.12065 -0.2794)
			(stroke
				(width 0.1)
				(type default)
			)
			(layer "B.Fab")
		)
		(fp_line
			(start 0.12065 -0.305054)
			(end 0.12065 -0.2794)
			(stroke
				(width 0.1)
				(type default)
			)
			(layer "B.Fab")
		)
		(fp_line
			(start -0.120396 0.3048)
			(end -0.120396 0.2794)
			(stroke
				(width 0.1)
				(type default)
			)
			(layer "B.Fab")
		)
		(fp_line
			(start -0.120396 0.2794)
			(end 0.12065 0.2794)
			(stroke
				(width 0.1)
				(type default)
			)
			(layer "B.Fab")
		)
		(fp_line
			(start -0.12065 -0.2794)
			(end -0.12065 -0.3048)
			(stroke
				(width 0.1)
				(type default)
			)
			(layer "B.Fab")
		)
		(fp_line
			(start -0.12065 -0.3048)
			(end -0.67945 -0.3048)
			(stroke
				(width 0.1)
				(type default)
			)
			(layer "B.Fab")
		)
		(fp_line
			(start -0.67945 0.3048)
			(end -0.120396 0.3048)
			(stroke
				(width 0.1)
				(type default)
			)
			(layer "B.Fab")
		)
		(fp_line
			(start -0.67945 -0.3048)
			(end -0.67945 0.3048)
			(stroke
				(width 0.1)
				(type default)
			)
			(layer "B.Fab")
		)
		(pad "1" smd circle
			(at 0.40005 0)
			(size 0 0)
			(layers "B.Cu" "B.Mask" "B.Paste")
			(net "PD_CHC_CPU1_DIMM_SAA")
		)
		(pad "2" smd circle
			(at -0.40005 0)
			(size 0 0)
			(layers "B.Cu" "B.Mask" "B.Paste")
			(net "GND")
		)
	)
)
